(kicad_pcb
	(version 20260206)
	(generator "pcbnew")
	(generator_version "10.0")
	(general
		(thickness 1.6)
		(legacy_teardrops no)
	)
	(paper "A4")
	(title_block
		(title "Bryce Canyon_IOM_M2_16342-2_OCP.brd")
		(comment 1 "Bryce Canyon / footprints 275-282 of 1146")
	)
	(layers
		(0 "F.Cu" signal "TOP")
		(4 "In1.Cu" signal "L2GND")
		(6 "In2.Cu" signal "L3")
		(8 "In3.Cu" signal "L4VCC")
		(10 "In4.Cu" signal "L5VCC")
		(12 "In5.Cu" signal "L6")
		(14 "In6.Cu" signal "L7GND")
		(2 "B.Cu" signal "BOTTOM")
		(9 "F.Adhes" user "F.Adhesive")
		(11 "B.Adhes" user "B.Adhesive")
		(13 "F.Paste" user "Package Geometry/Pastemask Top")
		(15 "B.Paste" user "Package Geometry/Pastemask Bottom")
		(5 "F.SilkS" user "Ref Des/Silkscreen Top")
		(7 "B.SilkS" user "Ref Des/Silkscreen Bottom")
		(1 "F.Mask" user "Board Geometry/Soldermask Top")
		(3 "B.Mask" user "Board Geometry/Soldermask Bottom")
		(17 "Dwgs.User" user "User.Drawings")
		(19 "Cmts.User" user "User.Comments")
		(21 "Eco1.User" user "User.Eco1")
		(23 "Eco2.User" user "User.Eco2")
		(25 "Edge.Cuts" user "Board Geometry/Outline")
		(27 "Margin" user)
		(31 "F.CrtYd" user "Package Geometry/Place Bound Top")
		(29 "B.CrtYd" user "Package Geometry/Place Bound Bottom")
		(35 "F.Fab" user "Ref Des/Assembly Top")
		(33 "B.Fab" user "Ref Des/Assembly Bottom")
	)
	(footprint ""
		(layer "F.Cu")
		(at 86.671404 -134.673086)
		(property "Reference" "R134"
			(at 0 0 0)
			(layer "F.SilkS")
			(hide yes)
			(effects
				(font
					(size 1.27 1.27)
				)
			)
		)
		(property "Value" "8K2R2J-3-GP"
			(at 0.064008 -3.993896 0)
			(unlocked yes)
			(layer "F.Fab")
			(hide yes)
			(effects
				(font
					(size 1.016 1.016)
					(thickness 0.1524)
				)
			)
		)
		(property "Device Type" "R402H16"
			(at 0.064008 -5.517896 0)
			(unlocked yes)
			(layer "F.Fab")
			(hide yes)
			(effects
				(font
					(size 1.016 1.016)
					(thickness 0.1524)
				)
			)
		)
		(duplicate_pad_numbers_are_jumpers no)
		(fp_line
			(start -0.508 -0.9398)
			(end -0.508 0.9398)
			(stroke
				(width 0.1524)
				(type default)
			)
			(layer "F.SilkS")
		)
		(fp_line
			(start 0.508 -0.9398)
			(end -0.508 -0.9398)
			(stroke
				(width 0.1524)
				(type default)
			)
			(layer "F.SilkS")
		)
		(fp_rect
			(start -0.508 0.9398)
			(end 0.508 -0.9398)
			(stroke
				(width 0)
				(type default)
			)
			(fill no)
			(layer "F.CrtYd")
		)
		(fp_rect
			(start -0.508 0.9398)
			(end 0.508 -0.9398)
			(stroke
				(width 0)
				(type default)
			)
			(fill no)
			(layer "F.Fab")
		)
		(pad "1" smd custom
			(at 0 -0.4445)
			(size 0.1397 0.1397)
			(layers "F.Cu" "F.Mask" "F.Paste")
			(net "P3V3_STBY")
			(options
				(clearance outline)
				(anchor circle)
			)
			(primitives
				(gr_poly
					(pts
						(arc
							(start -0.1778 -0.2794)
							(mid -0.249642 -0.249642)
							(end -0.2794 -0.1778)
						)
						(arc
							(start -0.2794 0.1778)
							(mid -0.249642 0.249642)
							(end -0.1778 0.2794)
						)
						(arc
							(start 0.1778 0.2794)
							(mid 0.249642 0.249642)
							(end 0.2794 0.1778)
						)
						(arc
							(start 0.2794 -0.1778)
							(mid 0.249642 -0.249642)
							(end 0.1778 -0.2794)
						)
					)
					(width 0)
					(fill yes)
				)
			)
		)
		(pad "2" smd custom
			(at 0 0.4445)
			(size 0.1397 0.1397)
			(layers "F.Cu" "F.Mask" "F.Paste")
			(net "EEPROM_A1")
			(options
				(clearance outline)
				(anchor circle)
			)
			(primitives
				(gr_poly
					(pts
						(arc
							(start -0.1778 -0.2794)
							(mid -0.249642 -0.249642)
							(end -0.2794 -0.1778)
						)
						(arc
							(start -0.2794 0.1778)
							(mid -0.249642 0.249642)
							(end -0.1778 0.2794)
						)
						(arc
							(start 0.1778 0.2794)
							(mid 0.249642 0.249642)
							(end 0.2794 0.1778)
						)
						(arc
							(start 0.2794 -0.1778)
							(mid 0.249642 -0.249642)
							(end 0.1778 -0.2794)
						)
					)
					(width 0)
					(fill yes)
				)
			)
		)
	)
	(footprint ""
		(layer "F.Cu")
		(at 60.4774 -139.9032)
		(property "Reference" "TP75"
			(at 0 0 0)
			(layer "F.SilkS")
			(hide yes)
			(effects
				(font
					(size 1.27 1.27)
				)
			)
		)
		(property "Value" "TPAD28-2-GP"
			(at -0.0127 -1.6637 0)
			(unlocked yes)
			(layer "F.Fab")
			(hide yes)
			(effects
				(font
					(size 1.016 1.016)
					(thickness 0.1524)
				)
			)
		)
		(property "Device Type" "TPAD28"
			(at -0.0127 -3.1877 0)
			(unlocked yes)
			(layer "F.Fab")
			(hide yes)
			(effects
				(font
					(size 1.016 1.016)
					(thickness 0.1524)
				)
			)
		)
		(duplicate_pad_numbers_are_jumpers no)
		(fp_poly
			(pts
				(arc
					(start 0.3556 0)
					(mid -0.3556 0)
					(end 0.3556 0)
				)
			)
			(stroke
				(width 0)
				(type default)
			)
			(fill no)
			(layer "F.CrtYd")
		)
		(fp_poly
			(pts
				(arc
					(start 0.6096 0)
					(mid -0.6096 0)
					(end 0.6096 0)
				)
			)
			(stroke
				(width 0)
				(type default)
			)
			(fill no)
			(layer "F.Fab")
		)
		(pad "1" smd circle
			(at 0 0)
			(size 0.7112 0.7112)
			(layers "F.Cu" "F.Mask" "F.Paste")
			(net "TP_BMC_GPIOI6")
		)
	)
	(footprint ""
		(layer "F.Cu")
		(at 53.0098 -160.1724 -90)
		(property "Reference" "C86"
			(at 0 0 270)
			(layer "F.SilkS")
			(hide yes)
			(effects
				(font
					(size 1.27 1.27)
				)
			)
		)
		(property "Value" "SCD1U16V2KX-3GP"
			(at 1.1811 -2.7051 270)
			(unlocked yes)
			(layer "F.Fab")
			(hide yes)
			(effects
				(font
					(size 1.016 1.016)
					(thickness 0.1524)
				)
			)
		)
		(property "Device Type" "C402H22"
			(at 1.1811 -4.2291 270)
			(unlocked yes)
			(layer "F.Fab")
			(hide yes)
			(effects
				(font
					(size 1.016 1.016)
					(thickness 0.1524)
				)
			)
		)
		(duplicate_pad_numbers_are_jumpers no)
		(fp_rect
			(start -0.4318 0.9525)
			(end 0.4318 -0.9525)
			(stroke
				(width 0)
				(type default)
			)
			(fill no)
			(layer "F.CrtYd")
		)
		(fp_rect
			(start -0.4318 0.9525)
			(end 0.4318 -0.9525)
			(stroke
				(width 0)
				(type default)
			)
			(fill no)
			(layer "F.Fab")
		)
		(pad "1" smd custom
			(at 0 -0.4445 270)
			(size 0.1524 0.1524)
			(layers "F.Cu" "F.Mask" "F.Paste")
			(net "ADCVREFFN")
			(options
				(clearance outline)
				(anchor circle)
			)
			(primitives
				(gr_poly
					(pts
						(arc
							(start 0.3048 -0.2032)
							(mid 0.275042 -0.275042)
							(end 0.2032 -0.3048)
						)
						(arc
							(start -0.2032 -0.3048)
							(mid -0.275042 -0.275042)
							(end -0.3048 -0.2032)
						)
						(arc
							(start -0.3048 0.2032)
							(mid -0.275042 0.275042)
							(end -0.2032 0.3048)
						)
						(arc
							(start 0.2032 0.3048)
							(mid 0.275042 0.275042)
							(end 0.3048 0.2032)
						)
					)
					(width 0)
					(fill yes)
				)
			)
		)
		(pad "2" smd custom
			(at 0 0.4445 270)
			(size 0.1524 0.1524)
			(layers "F.Cu" "F.Mask" "F.Paste")
			(net "ADCVREFFP")
			(options
				(clearance outline)
				(anchor circle)
			)
			(primitives
				(gr_poly
					(pts
						(arc
							(start 0.3048 -0.2032)
							(mid 0.275042 -0.275042)
							(end 0.2032 -0.3048)
						)
						(arc
							(start -0.2032 -0.3048)
							(mid -0.275042 -0.275042)
							(end -0.3048 -0.2032)
						)
						(arc
							(start -0.3048 0.2032)
							(mid -0.275042 0.275042)
							(end -0.2032 0.3048)
						)
						(arc
							(start 0.2032 0.3048)
							(mid 0.275042 0.275042)
							(end 0.3048 0.2032)
						)
					)
					(width 0)
					(fill yes)
				)
			)
		)
	)
	(footprint ""
		(layer "F.Cu")
		(at 191.7192 -134.2898)
		(property "Reference" "R845"
			(at 0 0 0)
			(layer "F.SilkS")
			(hide yes)
			(effects
				(font
					(size 1.27 1.27)
				)
			)
		)
		(property "Value" "4K7R2F-GP"
			(at 0.064008 -3.993896 0)
			(unlocked yes)
			(layer "F.Fab")
			(hide yes)
			(effects
				(font
					(size 1.016 1.016)
					(thickness 0.1524)
				)
			)
		)
		(property "Device Type" "R402H16"
			(at 0.064008 -5.517896 0)
			(unlocked yes)
			(layer "F.Fab")
			(hide yes)
			(effects
				(font
					(size 1.016 1.016)
					(thickness 0.1524)
				)
			)
		)
		(duplicate_pad_numbers_are_jumpers no)
		(fp_line
			(start -0.508 -0.9398)
			(end -0.508 0.9398)
			(stroke
				(width 0.1524)
				(type default)
			)
			(layer "F.SilkS")
		)
		(fp_line
			(start 0.508 -0.9398)
			(end -0.508 -0.9398)
			(stroke
				(width 0.1524)
				(type default)
			)
			(layer "F.SilkS")
		)
		(fp_rect
			(start -0.508 0.9398)
			(end 0.508 -0.9398)
			(stroke
				(width 0)
				(type default)
			)
			(fill no)
			(layer "F.CrtYd")
		)
		(fp_rect
			(start -0.508 0.9398)
			(end 0.508 -0.9398)
			(stroke
				(width 0)
				(type default)
			)
			(fill no)
			(layer "F.Fab")
		)
		(pad "1" smd custom
			(at 0 -0.4445)
			(size 0.1397 0.1397)
			(layers "F.Cu" "F.Mask" "F.Paste")
			(net "P3V3_STBY")
			(options
				(clearance outline)
				(anchor circle)
			)
			(primitives
				(gr_poly
					(pts
						(arc
							(start -0.1778 -0.2794)
							(mid -0.249642 -0.249642)
							(end -0.2794 -0.1778)
						)
						(arc
							(start -0.2794 0.1778)
							(mid -0.249642 0.249642)
							(end -0.1778 0.2794)
						)
						(arc
							(start 0.1778 0.2794)
							(mid 0.249642 0.249642)
							(end 0.2794 0.1778)
						)
						(arc
							(start 0.2794 -0.1778)
							(mid 0.249642 -0.249642)
							(end 0.1778 -0.2794)
						)
					)
					(width 0)
					(fill yes)
				)
			)
		)
		(pad "2" smd custom
			(at 0 0.4445)
			(size 0.1397 0.1397)
			(layers "F.Cu" "F.Mask" "F.Paste")
			(net "M2_1_ACTIVE_N")
			(options
				(clearance outline)
				(anchor circle)
			)
			(primitives
				(gr_poly
					(pts
						(arc
							(start -0.1778 -0.2794)
							(mid -0.249642 -0.249642)
							(end -0.2794 -0.1778)
						)
						(arc
							(start -0.2794 0.1778)
							(mid -0.249642 0.249642)
							(end -0.1778 0.2794)
						)
						(arc
							(start 0.1778 0.2794)
							(mid 0.249642 0.249642)
							(end 0.2794 0.1778)
						)
						(arc
							(start 0.2794 -0.1778)
							(mid 0.249642 -0.249642)
							(end 0.1778 -0.2794)
						)
					)
					(width 0)
					(fill yes)
				)
			)
		)
	)
	(footprint ""
		(layer "F.Cu")
		(at 165.629082 -134.66953 90)
		(property "Reference" "R822"
			(at 0 0 90)
			(layer "F.SilkS")
			(hide yes)
			(effects
				(font
					(size 1.27 1.27)
				)
			)
		)
		(property "Value" "0R2J-2-GP"
			(at 0.064008 -3.993896 90)
			(unlocked yes)
			(layer "F.Fab")
			(hide yes)
			(effects
				(font
					(size 1.016 1.016)
					(thickness 0.1524)
				)
			)
		)
		(property "Device Type" "R402H16"
			(at 0.064008 -5.517896 90)
			(unlocked yes)
			(layer "F.Fab")
			(hide yes)
			(effects
				(font
					(size 1.016 1.016)
					(thickness 0.1524)
				)
			)
		)
		(duplicate_pad_numbers_are_jumpers no)
		(fp_line
			(start 0.508 -0.9398)
			(end -0.508 -0.9398)
			(stroke
				(width 0.1524)
				(type default)
			)
			(layer "F.SilkS")
		)
		(fp_line
			(start -0.508 -0.9398)
			(end -0.508 0.9398)
			(stroke
				(width 0.1524)
				(type default)
			)
			(layer "F.SilkS")
		)
		(fp_rect
			(start -0.508 0.9398)
			(end 0.508 -0.9398)
			(stroke
				(width 0)
				(type default)
			)
			(fill no)
			(layer "F.CrtYd")
		)
		(fp_rect
			(start -0.508 0.9398)
			(end 0.508 -0.9398)
			(stroke
				(width 0)
				(type default)
			)
			(fill no)
			(layer "F.Fab")
		)
		(pad "1" smd custom
			(at 0 -0.4445 90)
			(size 0.1397 0.1397)
			(layers "F.Cu" "F.Mask" "F.Paste")
			(net "M2_2_PRESENT_N_R")
			(options
				(clearance outline)
				(anchor circle)
			)
			(primitives
				(gr_poly
					(pts
						(arc
							(start -0.1778 -0.2794)
							(mid -0.249642 -0.249642)
							(end -0.2794 -0.1778)
						)
						(arc
							(start -0.2794 0.1778)
							(mid -0.249642 0.249642)
							(end -0.1778 0.2794)
						)
						(arc
							(start 0.1778 0.2794)
							(mid 0.249642 0.249642)
							(end 0.2794 0.1778)
						)
						(arc
							(start 0.2794 -0.1778)
							(mid 0.249642 -0.249642)
							(end 0.1778 -0.2794)
						)
					)
					(width 0)
					(fill yes)
				)
			)
		)
		(pad "2" smd custom
			(at 0 0.4445 90)
			(size 0.1397 0.1397)
			(layers "F.Cu" "F.Mask" "F.Paste")
			(net "GND")
			(options
				(clearance outline)
				(anchor circle)
			)
			(primitives
				(gr_poly
					(pts
						(arc
							(start -0.1778 -0.2794)
							(mid -0.249642 -0.249642)
							(end -0.2794 -0.1778)
						)
						(arc
							(start -0.2794 0.1778)
							(mid -0.249642 0.249642)
							(end -0.1778 0.2794)
						)
						(arc
							(start 0.1778 0.2794)
							(mid 0.249642 0.249642)
							(end 0.2794 0.1778)
						)
						(arc
							(start 0.2794 -0.1778)
							(mid 0.249642 -0.249642)
							(end 0.1778 -0.2794)
						)
					)
					(width 0)
					(fill yes)
				)
			)
		)
	)
	(footprint ""
		(layer "F.Cu")
		(at 53.4416 -125.8062 90)
		(property "Reference" "R269"
			(at 0 0 90)
			(layer "F.SilkS")
			(hide yes)
			(effects
				(font
					(size 1.27 1.27)
				)
			)
		)
		(property "Value" "2K2R2J-2-GP"
			(at 0.064008 -3.993896 90)
			(unlocked yes)
			(layer "F.Fab")
			(hide yes)
			(effects
				(font
					(size 1.016 1.016)
					(thickness 0.1524)
				)
			)
		)
		(property "Device Type" "R402H16"
			(at 0.064008 -5.517896 90)
			(unlocked yes)
			(layer "F.Fab")
			(hide yes)
			(effects
				(font
					(size 1.016 1.016)
					(thickness 0.1524)
				)
			)
		)
		(duplicate_pad_numbers_are_jumpers no)
		(fp_line
			(start 0.508 -0.9398)
			(end -0.508 -0.9398)
			(stroke
				(width 0.1524)
				(type default)
			)
			(layer "F.SilkS")
		)
		(fp_line
			(start -0.508 -0.9398)
			(end -0.508 0.9398)
			(stroke
				(width 0.1524)
				(type default)
			)
			(layer "F.SilkS")
		)
		(fp_rect
			(start -0.508 0.9398)
			(end 0.508 -0.9398)
			(stroke
				(width 0)
				(type default)
			)
			(fill no)
			(layer "F.CrtYd")
		)
		(fp_rect
			(start -0.508 0.9398)
			(end 0.508 -0.9398)
			(stroke
				(width 0)
				(type default)
			)
			(fill no)
			(layer "F.Fab")
		)
		(pad "1" smd custom
			(at 0 -0.4445 90)
			(size 0.1397 0.1397)
			(layers "F.Cu" "F.Mask" "F.Paste")
			(net "P3V3_STBY")
			(options
				(clearance outline)
				(anchor circle)
			)
			(primitives
				(gr_poly
					(pts
						(arc
							(start -0.1778 -0.2794)
							(mid -0.249642 -0.249642)
							(end -0.2794 -0.1778)
						)
						(arc
							(start -0.2794 0.1778)
							(mid -0.249642 0.249642)
							(end -0.1778 0.2794)
						)
						(arc
							(start 0.1778 0.2794)
							(mid 0.249642 0.249642)
							(end 0.2794 0.1778)
						)
						(arc
							(start 0.2794 -0.1778)
							(mid 0.249642 -0.249642)
							(end 0.1778 -0.2794)
						)
					)
					(width 0)
					(fill yes)
				)
			)
		)
		(pad "2" smd custom
			(at 0 0.4445 90)
			(size 0.1397 0.1397)
			(layers "F.Cu" "F.Mask" "F.Paste")
			(net "FLA1_WP_N")
			(options
				(clearance outline)
				(anchor circle)
			)
			(primitives
				(gr_poly
					(pts
						(arc
							(start -0.1778 -0.2794)
							(mid -0.249642 -0.249642)
							(end -0.2794 -0.1778)
						)
						(arc
							(start -0.2794 0.1778)
							(mid -0.249642 0.249642)
							(end -0.1778 0.2794)
						)
						(arc
							(start 0.1778 0.2794)
							(mid 0.249642 0.249642)
							(end 0.2794 0.1778)
						)
						(arc
							(start 0.2794 -0.1778)
							(mid 0.249642 -0.249642)
							(end 0.1778 -0.2794)
						)
					)
					(width 0)
					(fill yes)
				)
			)
		)
	)
	(footprint ""
		(layer "F.Cu")
		(at 202.2094 -99.441)
		(property "Reference" "R558"
			(at 0 0 0)
			(layer "F.SilkS")
			(hide yes)
			(effects
				(font
					(size 1.27 1.27)
				)
			)
		)
		(property "Value" "0R2J-2-GP"
			(at 0.064008 -3.993896 0)
			(unlocked yes)
			(layer "F.Fab")
			(hide yes)
			(effects
				(font
					(size 1.016 1.016)
					(thickness 0.1524)
				)
			)
		)
		(property "Device Type" "R402H16"
			(at 0.064008 -5.517896 0)
			(unlocked yes)
			(layer "F.Fab")
			(hide yes)
			(effects
				(font
					(size 1.016 1.016)
					(thickness 0.1524)
				)
			)
		)
		(duplicate_pad_numbers_are_jumpers no)
		(fp_line
			(start -0.508 -0.9398)
			(end -0.508 0.9398)
			(stroke
				(width 0.1524)
				(type default)
			)
			(layer "F.SilkS")
		)
		(fp_line
			(start 0.508 -0.9398)
			(end -0.508 -0.9398)
			(stroke
				(width 0.1524)
				(type default)
			)
			(layer "F.SilkS")
		)
		(fp_rect
			(start -0.508 0.9398)
			(end 0.508 -0.9398)
			(stroke
				(width 0)
				(type default)
			)
			(fill no)
			(layer "F.CrtYd")
		)
		(fp_rect
			(start -0.508 0.9398)
			(end 0.508 -0.9398)
			(stroke
				(width 0)
				(type default)
			)
			(fill no)
			(layer "F.Fab")
		)
		(pad "1" smd custom
			(at 0 -0.4445)
			(size 0.1397 0.1397)
			(layers "F.Cu" "F.Mask" "F.Paste")
			(net "TEMP_2_SDA")
			(options
				(clearance outline)
				(anchor circle)
			)
			(primitives
				(gr_poly
					(pts
						(arc
							(start -0.1778 -0.2794)
							(mid -0.249642 -0.249642)
							(end -0.2794 -0.1778)
						)
						(arc
							(start -0.2794 0.1778)
							(mid -0.249642 0.249642)
							(end -0.1778 0.2794)
						)
						(arc
							(start 0.1778 0.2794)
							(mid 0.249642 0.249642)
							(end 0.2794 0.1778)
						)
						(arc
							(start 0.2794 -0.1778)
							(mid 0.249642 -0.249642)
							(end 0.1778 -0.2794)
						)
					)
					(width 0)
					(fill yes)
				)
			)
		)
		(pad "2" smd custom
			(at 0 0.4445)
			(size 0.1397 0.1397)
			(layers "F.Cu" "F.Mask" "F.Paste")
			(net "I2C_IOM_SDA")
			(options
				(clearance outline)
				(anchor circle)
			)
			(primitives
				(gr_poly
					(pts
						(arc
							(start -0.1778 -0.2794)
							(mid -0.249642 -0.249642)
							(end -0.2794 -0.1778)
						)
						(arc
							(start -0.2794 0.1778)
							(mid -0.249642 0.249642)
							(end -0.1778 0.2794)
						)
						(arc
							(start 0.1778 0.2794)
							(mid 0.249642 0.249642)
							(end 0.2794 0.1778)
						)
						(arc
							(start 0.2794 -0.1778)
							(mid 0.249642 -0.249642)
							(end 0.1778 -0.2794)
						)
					)
					(width 0)
					(fill yes)
				)
			)
		)
	)
	(footprint ""
		(layer "F.Cu")
		(at 155.716478 -6.088634 -90)
		(property "Reference" "R520"
			(at 0 0 270)
			(layer "F.SilkS")
			(hide yes)
			(effects
				(font
					(size 1.27 1.27)
				)
			)
		)
		(property "Value" "3D01R5F-GP"
			(at 0 -8.953754 270)
			(unlocked yes)
			(layer "F.Fab")
			(hide yes)
			(effects
				(font
					(size 1.27 1.016)
					(thickness 0.1524)
				)
			)
		)
		(property "Device Type" "R805H24"
			(at 0 -10.629646 270)
			(unlocked yes)
			(layer "F.Fab")
			(hide yes)
			(effects
				(font
					(size 1.27 1.016)
					(thickness 0.1524)
				)
			)
		)
		(duplicate_pad_numbers_are_jumpers no)
		(fp_line
			(start -0.888746 1.7018)
			(end 0.888746 1.7018)
			(stroke
				(width 0.1524)
				(type default)
			)
			(layer "F.SilkS")
		)
		(fp_line
			(start 0.888746 1.7018)
			(end 0.889 -0.508)
			(stroke
				(width 0.1524)
				(type default)
			)
			(layer "F.SilkS")
		)
		(fp_line
			(start -0.889 0.0762)
			(end -0.888746 1.7018)
			(stroke
				(width 0.1524)
				(type default)
			)
			(layer "F.SilkS")
		)
		(fp_line
			(start -0.888746 -1.7018)
			(end -0.889 0.2794)
			(stroke
				(width 0.1524)
				(type default)
			)
			(layer "F.SilkS")
		)
		(fp_line
			(start 0.888746 -1.7018)
			(end 0.889 -0.381)
			(stroke
				(width 0.1524)
				(type default)
			)
			(layer "F.SilkS")
		)
		(fp_line
			(start 0.888746 -1.7018)
			(end -0.888746 -1.7018)
			(stroke
				(width 0.1524)
				(type default)
			)
			(layer "F.SilkS")
		)
		(fp_poly
			(pts
				(xy 0.9652 -1.778) (xy 0.9652 1.778) (xy -0.9652 1.778) (xy -0.9652 -1.778)
			)
			(stroke
				(width 0)
				(type default)
			)
			(fill no)
			(layer "F.CrtYd")
		)
		(fp_rect
			(start -0.9652 1.778)
			(end 0.9652 -1.778)
			(stroke
				(width 0)
				(type default)
			)
			(fill no)
			(layer "F.Fab")
		)
		(pad "1" smd rect
			(at 0 -0.9652 270)
			(size 1.397 1.143)
			(layers "F.Cu" "F.Mask" "F.Paste")
			(net "P1V8_STBY_SNB")
		)
		(pad "2" smd rect
			(at 0 0.9652 270)
			(size 1.397 1.143)
			(layers "F.Cu" "F.Mask" "F.Paste")
			(net "GND")
		)
	)
)
